(kicad_pcb
	(version 20260206)
	(generator "pcbnew")
	(generator_version "10.0")
	(general
		(thickness 1.6)
		(legacy_teardrops no)
	)
	(paper "A4")
	(title_block
		(title "timecard-production-celestica-r4006 — R4006-B0001-02_R01.brd")
		(comment 1 "Time Appliance Project (Time Card) / footprints 47-52 of 1113")
	)
	(layers
		(0 "F.Cu" signal "TOP")
		(4 "In1.Cu" signal "L02_GND1")
		(6 "In2.Cu" signal "L03_SIG1")
		(8 "In3.Cu" signal "L04_GND2")
		(10 "In4.Cu" signal "L05_VCC1")
		(12 "In5.Cu" signal "L06_VCC2")
		(14 "In6.Cu" signal "L07_GND3")
		(16 "In7.Cu" signal "L08_SIG2")
		(18 "In8.Cu" signal "L09_GND4")
		(2 "B.Cu" signal "BOTTOM")
		(9 "F.Adhes" user "F.Adhesive")
		(11 "B.Adhes" user "B.Adhesive")
		(13 "F.Paste" user "Package Geometry/Pastemask Top")
		(15 "B.Paste" user "Package Geometry/Pastemask Bottom")
		(5 "F.SilkS" user "Ref Des/Silkscreen Top")
		(7 "B.SilkS" user "Ref Des/Silkscreen Bottom")
		(1 "F.Mask" user "Board Geometry/Soldermask Top")
		(3 "B.Mask" user "Board Geometry/Soldermask Bottom")
		(17 "Dwgs.User" user "User.Drawings")
		(19 "Cmts.User" user "User.Comments")
		(21 "Eco1.User" user "User.Eco1")
		(23 "Eco2.User" user "User.Eco2")
		(25 "Edge.Cuts" user "Board Geometry/Outline")
		(27 "Margin" user)
		(31 "F.CrtYd" user "Package Geometry/Place Bound Top")
		(29 "B.CrtYd" user "Package Geometry/Place Bound Bottom")
		(35 "F.Fab" user "Ref Des/Assembly Top")
		(33 "B.Fab" user "Ref Des/Assembly Bottom")
	)
	(footprint ""
		(layer "F.Cu")
		(at 54.102 -130.429)
		(property "Reference" "SP51"
			(at 0 0 0)
			(layer "F.SilkS")
			(hide yes)
			(effects
				(font
					(size 1.27 1.27)
				)
			)
		)
		(property "Value" ""
			(at 0 0 0)
			(layer "F.Fab")
			(effects
				(font
					(size 1.27 1.27)
				)
			)
		)
		(duplicate_pad_numbers_are_jumpers no)
	)
	(footprint ""
		(layer "F.Cu")
		(at 4.572 -81.534 90)
		(property "Reference" "R397"
			(at -2.667 -0.97663 90)
			(unlocked yes)
			(layer "F.SilkS")
			(effects
				(font
					(size 0.7874 0.5842)
					(thickness 0.1524)
				)
			)
		)
		(property "Value" "VAL*"
			(at 0.02032 2.13233 90)
			(unlocked yes)
			(layer "F.Fab")
			(hide yes)
			(effects
				(font
					(size 0.7874 0.5842)
					(thickness 0.1524)
				)
			)
		)
		(property "Tolerance" "TOL*"
			(at 0.044704 3.05435 90)
			(unlocked yes)
			(layer "Cmts.User")
			(hide yes)
			(effects
				(font
					(size 0.7874 0.5842)
					(thickness 0.1524)
				)
			)
		)
		(property "User Part Number" "PARTNUM*"
			(at 0.02032 4.024884 90)
			(unlocked yes)
			(layer "Cmts.User")
			(hide yes)
			(effects
				(font
					(size 0.7874 0.5842)
					(thickness 0.1524)
				)
			)
		)
		(property "Device Type" "RESISTOR-G155-133R0-01,33OHM,1%"
			(at 0.008382 1.210564 90)
			(unlocked yes)
			(layer "F.Fab")
			(hide yes)
			(effects
				(font
					(size 0.7874 0.5842)
					(thickness 0.1524)
				)
			)
		)
		(duplicate_pad_numbers_are_jumpers no)
		(fp_line
			(start 1.143 -0.5588)
			(end -1.143 -0.5588)
			(stroke
				(width 0.1)
				(type default)
			)
			(layer "F.SilkS")
		)
		(fp_line
			(start -1.143 -0.5588)
			(end -1.143 0.5588)
			(stroke
				(width 0.1)
				(type default)
			)
			(layer "F.SilkS")
		)
		(fp_line
			(start 1.143 0.5588)
			(end 1.143 -0.5588)
			(stroke
				(width 0.1)
				(type default)
			)
			(layer "F.SilkS")
		)
		(fp_line
			(start -1.143 0.5588)
			(end 1.143 0.5588)
			(stroke
				(width 0.1)
				(type default)
			)
			(layer "F.SilkS")
		)
		(fp_rect
			(start -1.143 -0.5588)
			(end 1.143 0.5588)
			(stroke
				(width 0)
				(type default)
			)
			(fill no)
			(layer "F.CrtYd")
		)
		(fp_line
			(start 0.508 -0.3048)
			(end -0.508 -0.3048)
			(stroke
				(width 0.1)
				(type default)
			)
			(layer "F.Fab")
		)
		(fp_line
			(start -0.508 -0.3048)
			(end -0.508 0.3048)
			(stroke
				(width 0.1)
				(type default)
			)
			(layer "F.Fab")
		)
		(fp_line
			(start 0.508 0.3048)
			(end 0.508 -0.3048)
			(stroke
				(width 0.1)
				(type default)
			)
			(layer "F.Fab")
		)
		(fp_line
			(start -0.508 0.3048)
			(end 0.508 0.3048)
			(stroke
				(width 0.1)
				(type default)
			)
			(layer "F.Fab")
		)
		(pad "1" smd rect
			(at -0.5334 0 90)
			(size 0.7112 0.6096)
			(layers "F.Cu" "F.Mask" "F.Paste")
			(net "GPS_SMA_LED_BLUE_N")
		)
		(pad "2" smd rect
			(at 0.5334 0 90)
			(size 0.7112 0.6096)
			(layers "F.Cu" "F.Mask" "F.Paste")
			(net "UNNAMED_14_LED4PV14_I269_1")
		)
		(zone
			(layer "F.Cu")
			(hatch none 0.5)
			(connect_pads
				(clearance 0)
			)
			(min_thickness 0.25)
			(keepout
				(tracks not_allowed)
				(vias allowed)
				(pads allowed)
				(copperpour not_allowed)
				(footprints allowed)
			)
			(placement
				(enabled no)
				(sheetname "")
			)
			(fill
				(thermal_gap 0.5)
				(thermal_bridge_width 0.5)
				(island_removal_mode 0)
			)
			(polygon
				(pts
					(xy 4.2672 -81.4578) (xy 4.8768 -81.4578) (xy 4.8768 -81.6102) (xy 4.2672 -81.6102)
				)
			)
		)
		(zone
			(layer "F.Cu")
			(hatch none 0.5)
			(connect_pads
				(clearance 0)
			)
			(min_thickness 0.25)
			(keepout
				(tracks allowed)
				(vias not_allowed)
				(pads allowed)
				(copperpour not_allowed)
				(footprints allowed)
			)
			(placement
				(enabled no)
				(sheetname "")
			)
			(fill
				(thermal_gap 0.5)
				(thermal_bridge_width 0.5)
				(island_removal_mode 0)
			)
			(polygon
				(pts
					(xy 4.2672 -81.4578) (xy 4.8768 -81.4578) (xy 4.8768 -81.6102) (xy 4.2672 -81.6102)
				)
			)
		)
	)
	(footprint ""
		(layer "F.Cu")
		(at 124.587 -43.688)
		(property "Reference" "R212"
			(at 3.048 -1.35763 0)
			(unlocked yes)
			(layer "F.SilkS")
			(effects
				(font
					(size 0.7874 0.5842)
					(thickness 0.1524)
				)
			)
		)
		(property "Value" "VAL*"
			(at 0.02032 2.13233 0)
			(unlocked yes)
			(layer "F.Fab")
			(hide yes)
			(effects
				(font
					(size 0.7874 0.5842)
					(thickness 0.1524)
				)
			)
		)
		(property "Device Type" "RESISTOR-G155-11000-01,100OHM,A"
			(at 0.008382 1.210564 0)
			(unlocked yes)
			(layer "F.Fab")
			(hide yes)
			(effects
				(font
					(size 0.7874 0.5842)
					(thickness 0.1524)
				)
			)
		)
		(property "User Part Number" "PARTNUM*"
			(at 0.02032 4.024884 0)
			(unlocked yes)
			(layer "Cmts.User")
			(hide yes)
			(effects
				(font
					(size 0.7874 0.5842)
					(thickness 0.1524)
				)
			)
		)
		(property "Tolerance" "TOL*"
			(at 0.044704 3.05435 0)
			(unlocked yes)
			(layer "Cmts.User")
			(hide yes)
			(effects
				(font
					(size 0.7874 0.5842)
					(thickness 0.1524)
				)
			)
		)
		(duplicate_pad_numbers_are_jumpers no)
		(fp_line
			(start -1.143 -0.5588)
			(end -1.143 0.5588)
			(stroke
				(width 0.1)
				(type default)
			)
			(layer "F.SilkS")
		)
		(fp_line
			(start -1.143 0.5588)
			(end 1.143 0.5588)
			(stroke
				(width 0.1)
				(type default)
			)
			(layer "F.SilkS")
		)
		(fp_line
			(start 1.143 -0.5588)
			(end -1.143 -0.5588)
			(stroke
				(width 0.1)
				(type default)
			)
			(layer "F.SilkS")
		)
		(fp_line
			(start 1.143 0.5588)
			(end 1.143 -0.5588)
			(stroke
				(width 0.1)
				(type default)
			)
			(layer "F.SilkS")
		)
		(fp_rect
			(start -1.143 0.5588)
			(end 1.143 -0.5588)
			(stroke
				(width 0)
				(type default)
			)
			(fill no)
			(layer "F.CrtYd")
		)
		(fp_line
			(start -0.508 -0.3048)
			(end -0.508 0.3048)
			(stroke
				(width 0.1)
				(type default)
			)
			(layer "F.Fab")
		)
		(fp_line
			(start -0.508 0.3048)
			(end 0.508 0.3048)
			(stroke
				(width 0.1)
				(type default)
			)
			(layer "F.Fab")
		)
		(fp_line
			(start 0.508 -0.3048)
			(end -0.508 -0.3048)
			(stroke
				(width 0.1)
				(type default)
			)
			(layer "F.Fab")
		)
		(fp_line
			(start 0.508 0.3048)
			(end 0.508 -0.3048)
			(stroke
				(width 0.1)
				(type default)
			)
			(layer "F.Fab")
		)
		(pad "1" smd rect
			(at -0.5334 0)
			(size 0.7112 0.6096)
			(layers "F.Cu" "F.Mask" "F.Paste")
			(net "FPGA_M0")
		)
		(pad "2" smd rect
			(at 0.5334 0)
			(size 0.7112 0.6096)
			(layers "F.Cu" "F.Mask" "F.Paste")
			(net "SG")
		)
		(zone
			(layer "F.Cu")
			(hatch none 0.5)
			(connect_pads
				(clearance 0)
			)
			(min_thickness 0.25)
			(keepout
				(tracks allowed)
				(vias not_allowed)
				(pads allowed)
				(copperpour not_allowed)
				(footprints allowed)
			)
			(placement
				(enabled no)
				(sheetname "")
			)
			(fill
				(thermal_gap 0.5)
				(thermal_bridge_width 0.5)
				(island_removal_mode 0)
			)
			(polygon
				(pts
					(xy 124.5108 -43.3832) (xy 124.6632 -43.3832) (xy 124.6632 -43.9928) (xy 124.5108 -43.9928)
				)
			)
		)
	)
	(footprint ""
		(layer "F.Cu")
		(at 49.8094 -100.9904)
		(property "Reference" "L1"
			(at 0.1016 4.63677 0)
			(unlocked yes)
			(layer "F.SilkS")
			(effects
				(font
					(size 0.7874 0.5842)
					(thickness 0.1524)
				)
			)
		)
		(property "Value" "VAL*"
			(at -0.035306 8.510778 0)
			(unlocked yes)
			(layer "F.Fab")
			(hide yes)
			(effects
				(font
					(size 0.7874 0.5842)
					(thickness 0.1524)
				)
			)
		)
		(property "Tolerance" "TOL*"
			(at -0.061722 7.222744 0)
			(unlocked yes)
			(layer "Cmts.User")
			(hide yes)
			(effects
				(font
					(size 0.7874 0.5842)
					(thickness 0.1524)
				)
			)
		)
		(property "User Part Number" "PARTNUM*"
			(at 0 6.106668 0)
			(unlocked yes)
			(layer "Cmts.User")
			(hide yes)
			(effects
				(font
					(size 0.7874 0.5842)
					(thickness 0.1524)
				)
			)
		)
		(property "Device Type" "INDUCTOR_2-G190-10424-01,4.7UHA"
			(at 0 4.912868 0)
			(unlocked yes)
			(layer "F.Fab")
			(hide yes)
			(effects
				(font
					(size 0.7874 0.5842)
					(thickness 0.1524)
				)
			)
		)
		(duplicate_pad_numbers_are_jumpers no)
		(fp_line
			(start -4.448302 -3.803904)
			(end 4.448302 -3.803904)
			(stroke
				(width 0.1)
				(type default)
			)
			(layer "F.SilkS")
		)
		(fp_line
			(start -4.448302 3.803904)
			(end -4.448302 -3.803904)
			(stroke
				(width 0.1)
				(type default)
			)
			(layer "F.SilkS")
		)
		(fp_line
			(start 4.448302 -3.803904)
			(end 4.448302 3.803904)
			(stroke
				(width 0.1)
				(type default)
			)
			(layer "F.SilkS")
		)
		(fp_line
			(start 4.448302 3.803904)
			(end -4.448302 3.803904)
			(stroke
				(width 0.1)
				(type default)
			)
			(layer "F.SilkS")
		)
		(fp_rect
			(start 4.702302 -4.057904)
			(end -4.702302 4.057904)
			(stroke
				(width 0)
				(type default)
			)
			(fill no)
			(layer "F.CrtYd")
		)
		(fp_line
			(start -3.800094 -3.549904)
			(end 3.800094 -3.549904)
			(stroke
				(width 0.1)
				(type default)
			)
			(layer "F.Fab")
		)
		(fp_line
			(start -3.800094 3.549904)
			(end -3.800094 -3.549904)
			(stroke
				(width 0.1)
				(type default)
			)
			(layer "F.Fab")
		)
		(fp_line
			(start 3.800094 -3.549904)
			(end 3.800094 3.549904)
			(stroke
				(width 0.1)
				(type default)
			)
			(layer "F.Fab")
		)
		(fp_line
			(start 3.800094 3.549904)
			(end -3.800094 3.549904)
			(stroke
				(width 0.1)
				(type default)
			)
			(layer "F.Fab")
		)
		(fp_text user "1"
			(at -3.7084 4.50977 0)
			(unlocked yes)
			(layer "F.SilkS")
			(effects
				(font
					(size 0.7874 0.5842)
					(thickness 0.1524)
				)
			)
		)
		(fp_text user "2"
			(at 4.0386 4.50977 0)
			(unlocked yes)
			(layer "F.SilkS")
			(effects
				(font
					(size 0.7874 0.5842)
					(thickness 0.1524)
				)
			)
		)
		(fp_text user "1"
			(at -4.3434 0.30607 0)
			(unlocked yes)
			(layer "F.Fab")
			(effects
				(font
					(size 0.7874 0.5842)
					(thickness 0.1524)
				)
			)
		)
		(fp_text user "2"
			(at 4.5466 0.05207 0)
			(unlocked yes)
			(layer "F.Fab")
			(effects
				(font
					(size 0.7874 0.5842)
					(thickness 0.1524)
				)
			)
		)
		(pad "1" smd rect
			(at -2.975102 0)
			(size 2.4384 3.7084)
			(layers "F.Cu" "F.Mask" "F.Paste")
			(net "XP5R0V_SW")
		)
		(pad "2" smd rect
			(at 2.975102 0)
			(size 2.4384 3.7084)
			(layers "F.Cu" "F.Mask" "F.Paste")
			(net "XP5R0V")
		)
		(zone
			(layer "F.Cu")
			(hatch none 0.5)
			(connect_pads
				(clearance 0)
			)
			(min_thickness 0.25)
			(keepout
				(tracks allowed)
				(vias not_allowed)
				(pads allowed)
				(copperpour not_allowed)
				(footprints allowed)
			)
			(placement
				(enabled no)
				(sheetname "")
			)
			(fill
				(thermal_gap 0.5)
				(thermal_bridge_width 0.5)
				(island_removal_mode 0)
			)
			(polygon
				(pts
					(xy 46.009306 -97.440496) (xy 46.009306 -99.1362) (xy 48.053498 -99.1362) (xy 48.053498 -102.8446)
					(xy 46.009306 -102.8446) (xy 46.009306 -104.540304) (xy 53.609494 -104.540304) (xy 53.609494 -102.8446)
					(xy 51.565302 -102.8446) (xy 51.565302 -99.1362) (xy 53.609494 -99.1362) (xy 53.609494 -97.440496)
				)
			)
		)
	)
	(footprint ""
		(layer "F.Cu")
		(at 28.575 -75.184 -90)
		(property "Reference" "R352"
			(at -0.381 -2.45237 90)
			(unlocked yes)
			(layer "F.SilkS")
			(effects
				(font
					(size 0.7874 0.5842)
					(thickness 0.1524)
				)
			)
		)
		(property "Value" "VAL*"
			(at 0.02032 2.13233 270)
			(unlocked yes)
			(layer "F.Fab")
			(hide yes)
			(effects
				(font
					(size 0.7874 0.5842)
					(thickness 0.1524)
				)
			)
		)
		(property "Tolerance" "TOL*"
			(at 0.044704 3.05435 270)
			(unlocked yes)
			(layer "Cmts.User")
			(hide yes)
			(effects
				(font
					(size 0.7874 0.5842)
					(thickness 0.1524)
				)
			)
		)
		(property "User Part Number" "PARTNUM*"
			(at 0.02032 4.024884 270)
			(unlocked yes)
			(layer "Cmts.User")
			(hide yes)
			(effects
				(font
					(size 0.7874 0.5842)
					(thickness 0.1524)
				)
			)
		)
		(property "Device Type" "RESISTOR-G155-11000-01,100OHM,A"
			(at 0.008382 1.210564 270)
			(unlocked yes)
			(layer "F.Fab")
			(hide yes)
			(effects
				(font
					(size 0.7874 0.5842)
					(thickness 0.1524)
				)
			)
		)
		(duplicate_pad_numbers_are_jumpers no)
		(fp_line
			(start -1.143 0.5588)
			(end 1.143 0.5588)
			(stroke
				(width 0.1)
				(type default)
			)
			(layer "F.SilkS")
		)
		(fp_line
			(start 1.143 0.5588)
			(end 1.143 -0.5588)
			(stroke
				(width 0.1)
				(type default)
			)
			(layer "F.SilkS")
		)
		(fp_line
			(start -1.143 -0.5588)
			(end -1.143 0.5588)
			(stroke
				(width 0.1)
				(type default)
			)
			(layer "F.SilkS")
		)
		(fp_line
			(start 1.143 -0.5588)
			(end -1.143 -0.5588)
			(stroke
				(width 0.1)
				(type default)
			)
			(layer "F.SilkS")
		)
		(fp_poly
			(pts
				(xy -1.143 0.5588) (xy 1.143 0.5588) (xy 1.143 -0.5588) (xy -1.143 -0.5588)
			)
			(stroke
				(width 0)
				(type default)
			)
			(fill no)
			(layer "F.CrtYd")
		)
		(fp_line
			(start -0.508 0.3048)
			(end 0.508 0.3048)
			(stroke
				(width 0.1)
				(type default)
			)
			(layer "F.Fab")
		)
		(fp_line
			(start 0.508 0.3048)
			(end 0.508 -0.3048)
			(stroke
				(width 0.1)
				(type default)
			)
			(layer "F.Fab")
		)
		(fp_line
			(start -0.508 -0.3048)
			(end -0.508 0.3048)
			(stroke
				(width 0.1)
				(type default)
			)
			(layer "F.Fab")
		)
		(fp_line
			(start 0.508 -0.3048)
			(end -0.508 -0.3048)
			(stroke
				(width 0.1)
				(type default)
			)
			(layer "F.Fab")
		)
		(pad "1" smd rect
			(at -0.5334 0 270)
			(size 0.7112 0.6096)
			(layers "F.Cu" "F.Mask" "F.Paste")
			(net "R_FT4232_CHC_RX")
		)
		(pad "2" smd rect
			(at 0.5334 0 270)
			(size 0.7112 0.6096)
			(layers "F.Cu" "F.Mask" "F.Paste")
			(net "UART_FT4232_RX_FPGA_TX")
		)
		(zone
			(layer "F.Cu")
			(hatch none 0.5)
			(connect_pads
				(clearance 0)
			)
			(min_thickness 0.25)
			(keepout
				(tracks not_allowed)
				(vias allowed)
				(pads allowed)
				(copperpour not_allowed)
				(footprints allowed)
			)
			(placement
				(enabled no)
				(sheetname "")
			)
			(fill
				(thermal_gap 0.5)
				(thermal_bridge_width 0.5)
				(island_removal_mode 0)
			)
			(polygon
				(pts
					(xy 28.2702 -75.2602) (xy 28.2702 -75.1078) (xy 28.8798 -75.1078) (xy 28.8798 -75.2602)
				)
			)
		)
		(zone
			(layer "F.Cu")
			(hatch none 0.5)
			(connect_pads
				(clearance 0)
			)
			(min_thickness 0.25)
			(keepout
				(tracks allowed)
				(vias not_allowed)
				(pads allowed)
				(copperpour not_allowed)
				(footprints allowed)
			)
			(placement
				(enabled no)
				(sheetname "")
			)
			(fill
				(thermal_gap 0.5)
				(thermal_bridge_width 0.5)
				(island_removal_mode 0)
			)
			(polygon
				(pts
					(xy 28.2702 -75.2602) (xy 28.2702 -75.1078) (xy 28.8798 -75.1078) (xy 28.8798 -75.2602)
				)
			)
		)
	)
	(footprint ""
		(layer "F.Cu")
		(at 133.223 -40.513)
		(property "Reference" "C175"
			(at 4.445 6.13537 0)
			(unlocked yes)
			(layer "F.SilkS")
			(effects
				(font
					(size 0.7874 0.5842)
					(thickness 0.1524)
				)
			)
		)
		(property "Value" "VAL*"
			(at 0.1016 3.769106 0)
			(unlocked yes)
			(layer "F.Fab")
			(hide yes)
			(effects
				(font
					(size 0.7874 0.5842)
					(thickness 0.1524)
				)
			)
		)
		(property "Tolerance" "TOL*"
			(at 0.127 4.734306 0)
			(unlocked yes)
			(layer "Cmts.User")
			(hide yes)
			(effects
				(font
					(size 0.7874 0.5842)
					(thickness 0.1524)
				)
			)
		)
		(property "User Part Number" "PARTNUM*"
			(at 0.2032 5.801106 0)
			(unlocked yes)
			(layer "Cmts.User")
			(hide yes)
			(effects
				(font
					(size 0.7874 0.5842)
					(thickness 0.1524)
				)
			)
		)
		(property "Device Type" "CAPACITOR-G109-0G107-BM,100UF,A"
			(at 0.0762 2.829306 0)
			(unlocked yes)
			(layer "F.Fab")
			(hide yes)
			(effects
				(font
					(size 0.7874 0.5842)
					(thickness 0.1524)
				)
			)
		)
		(duplicate_pad_numbers_are_jumpers no)
		(fp_line
			(start -2.159 -1.5748)
			(end 2.159 -1.5748)
			(stroke
				(width 0.1)
				(type default)
			)
			(layer "F.SilkS")
		)
		(fp_line
			(start -2.159 1.5748)
			(end -2.159 -1.5748)
			(stroke
				(width 0.1)
				(type default)
			)
			(layer "F.SilkS")
		)
		(fp_line
			(start 2.159 -1.5748)
			(end 2.159 1.5748)
			(stroke
				(width 0.1)
				(type default)
			)
			(layer "F.SilkS")
		)
		(fp_line
			(start 2.159 1.5748)
			(end -2.159 1.5748)
			(stroke
				(width 0.1)
				(type default)
			)
			(layer "F.SilkS")
		)
		(fp_rect
			(start -2.159 -1.5748)
			(end 2.159 1.5748)
			(stroke
				(width 0)
				(type default)
			)
			(fill no)
			(layer "F.CrtYd")
		)
		(fp_line
			(start -1.6002 -1.2446)
			(end -1.6002 1.2446)
			(stroke
				(width 0.1)
				(type default)
			)
			(layer "F.Fab")
		)
		(fp_line
			(start -1.6002 1.2446)
			(end 1.6002 1.2446)
			(stroke
				(width 0.1)
				(type default)
			)
			(layer "F.Fab")
		)
		(fp_line
			(start 1.6002 -1.2446)
			(end -1.6002 -1.2446)
			(stroke
				(width 0.1)
				(type default)
			)
			(layer "F.Fab")
		)
		(fp_line
			(start 1.6002 1.2446)
			(end 1.6002 -1.2446)
			(stroke
				(width 0.1)
				(type default)
			)
			(layer "F.Fab")
		)
		(pad "1" smd rect
			(at -1.3335 0)
			(size 1.143 2.6416)
			(layers "F.Cu" "F.Mask" "F.Paste")
			(net "XP1R0V_FPGA_VCCINT")
		)
		(pad "2" smd rect
			(at 1.3335 0)
			(size 1.143 2.6416)
			(layers "F.Cu" "F.Mask" "F.Paste")
			(net "SG")
		)
		(zone
			(layer "F.Cu")
			(hatch none 0.5)
			(connect_pads
				(clearance 0)
			)
			(min_thickness 0.25)
			(keepout
				(tracks allowed)
				(vias not_allowed)
				(pads allowed)
				(copperpour not_allowed)
				(footprints allowed)
			)
			(placement
				(enabled no)
				(sheetname "")
			)
			(fill
				(thermal_gap 0.5)
				(thermal_bridge_width 0.5)
				(island_removal_mode 0)
			)
			(polygon
				(pts
					(xy 132.5372 -41.91) (xy 132.5372 -39.116) (xy 133.9088 -39.116) (xy 133.9088 -41.91)
				)
			)
		)
	)
)
